(kicad_pcb
	(version 20221018)
	(generator pcbnew)
	(general
    (thickness 1.62)
  )
	(paper "A4")
	(title_block
    (title "ECP5 - Datacenter Secure Control Module (DC-SCM)")
    (date "2024-07-01")
    (rev "1.2.1")
		(comment 9 "footprints 150-157 of 506")
	)
	(layers
    (0 "F.Cu" signal)
    (1 "In1.Cu" power)
    (2 "In2.Cu" signal)
    (3 "In3.Cu" power)
    (4 "In4.Cu" power)
    (5 "In5.Cu" signal)
    (6 "In6.Cu" power)
    (31 "B.Cu" signal)
    (32 "B.Adhes" user "B.Adhesive")
    (33 "F.Adhes" user "F.Adhesive")
    (34 "B.Paste" user)
    (35 "F.Paste" user)
    (36 "B.SilkS" user "B.Silkscreen")
    (37 "F.SilkS" user "F.Silkscreen")
    (38 "B.Mask" user)
    (39 "F.Mask" user)
    (40 "Dwgs.User" user "User.Drawings")
    (41 "Cmts.User" user "User.Comments")
    (42 "Eco1.User" user "User.Eco1")
    (43 "Eco2.User" user "User.Eco2")
    (44 "Edge.Cuts" user)
    (45 "Margin" user)
    (46 "B.CrtYd" user "B.Courtyard")
    (47 "F.CrtYd" user "F.Courtyard")
    (48 "B.Fab" user)
    (49 "F.Fab" user)
  )
	(footprint "antmicro-footprints:C_0402_1005Metric" (layer "F.Cu")
    (at 92.05 85.1)
    (descr "Capacitor SMD 0402")
    (tags "capacitor SMD 0402")
    (property "Author" "Antmicro")
    (property "Dielectric" "")
    (property "License" "Apache-2.0")
    (property "MPN" "CC0402MRX5R5BB106")
    (property "Manufacturer" "YAGEO")
    (property "Public" "False")
    (property "Sheetfile" "power-supply.kicad_sch")
    (property "Sheetname" "Power supply")
    (property "Val" "10u")
    (property "Voltage" "")
    (property "ki_description" "SMD Multilayer Ceramic Capacitor, 10 µF, 6.3 V, 0402 [1005 Metric], ± 20%, X5R, CC Series")
    (property "ki_keywords" "0402, SMT, CAPACITOR, PASSIVE, MLCC, CERAMIC")
    (attr smd)
    (fp_text reference "C132" (at 2.32 0.415) (layer "F.SilkS")
        (effects (font (size 0.7 0.7) (thickness 0.127)))
    )
    (fp_text value "C_10u_0402" (at 0 1.17) (layer "F.Fab")
        (effects (font (size 1 1) (thickness 0.15)))
    )
    (fp_text user "${REFERENCE}" (at 0 0) (layer "F.Fab")
        (effects (font (size 0.25 0.25) (thickness 0.04)))
    )
    (fp_text user "Author: Antmicro" (at -0.939 3.399) (layer "F.Fab") hide
        (effects (font (size 0.7 0.7) (thickness 0.15)) (justify left bottom))
    )
    (fp_text user "License: Apache-2.0" (at -0.939 5.799) (layer "F.Fab") hide
        (effects (font (size 0.7 0.7) (thickness 0.15)) (justify left bottom))
    )
    (fp_rect (start -0.925 -0.47) (end 0.925 0.47)
      (stroke (width 0.05) (type default)) (fill none) (layer "F.CrtYd"))
    (fp_line (start -0.494 -0.25) (end 0.504 -0.25)
      (stroke (width 0.15) (type solid)) (layer "F.Fab"))
    (fp_line (start -0.494 0.248) (end -0.494 -0.25)
      (stroke (width 0.15) (type solid)) (layer "F.Fab"))
    (fp_line (start 0.504 -0.25) (end 0.504 0.248)
      (stroke (width 0.15) (type solid)) (layer "F.Fab"))
    (fp_line (start 0.504 0.248) (end -0.494 0.248)
      (stroke (width 0.15) (type solid)) (layer "F.Fab"))
    (pad "1" smd roundrect (at -0.48 0) (size 0.59 0.64) (layers "F.Cu" "F.Paste" "F.Mask") (roundrect_rratio 0.25)
      (net 1 "GND") (pintype "passive"))
    (pad "2" smd roundrect (at 0.48 0) (size 0.59 0.64) (layers "F.Cu" "F.Paste" "F.Mask") (roundrect_rratio 0.25)
      (net 359 "Net-(C122-Pad2)") (pintype "passive"))
  )
	(footprint "antmicro-footprints:R_0402_1005Metric" (layer "F.Cu")
    (at 88.635 88.7)
    (descr "Resistor SMD 0402")
    (tags "resistor SMD 0402")
    (property "Author" "Antmicro")
    (property "License" "Apache-2.0")
    (property "MPN" "CR0402-FX-1003GLF")
    (property "Manufacturer" "Bourns")
    (property "Public" "False")
    (property "Sheetfile" "power-supply.kicad_sch")
    (property "Sheetname" "Power supply")
    (property "Tolerance" "1%")
    (property "Val" "100k")
    (property "ki_description" "SMD Chip Resistor, 100 kohm, ± 1%, 62.5 mW, 0402 [1005 Metric], Thick Film, General Purpose")
    (property "ki_keywords" "0402, SMT, RESISTOR, PASSIVE")
    (attr smd)
    (fp_text reference "R123" (at -0.235 1.05) (layer "F.SilkS")
        (effects (font (size 0.7 0.7) (thickness 0.127)))
    )
    (fp_text value "R_100k_0402" (at 0 1.17) (layer "F.Fab")
        (effects (font (size 1 1) (thickness 0.15)))
    )
    (fp_text user "${REFERENCE}" (at 0 0) (layer "F.Fab")
        (effects (font (size 0.25 0.25) (thickness 0.04)))
    )
    (fp_text user "License: Apache-2.0" (at -0.95 5.169) (layer "F.Fab") hide
        (effects (font (size 0.7 0.7) (thickness 0.15)) (justify left bottom))
    )
    (fp_text user "Author: Antmicro" (at -0.95 4.169) (layer "F.Fab") hide
        (effects (font (size 0.7 0.7) (thickness 0.15)) (justify left bottom))
    )
    (fp_rect (start -0.925 -0.47) (end 0.925 0.47)
      (stroke (width 0.05) (type default)) (fill none) (layer "F.CrtYd"))
    (fp_rect (start -0.5 -0.25) (end 0.5 0.25)
      (stroke (width 0.15) (type solid)) (fill none) (layer "F.Fab"))
    (pad "1" smd roundrect (at -0.48 0) (size 0.59 0.64) (layers "F.Cu" "F.Paste" "F.Mask") (roundrect_rratio 0.25)
      (net 301 "Net-(U16-FB)") (pintype "passive"))
    (pad "2" smd roundrect (at 0.48 0) (size 0.59 0.64) (layers "F.Cu" "F.Paste" "F.Mask") (roundrect_rratio 0.25)
      (net 1 "GND") (pintype "passive"))
  )
	(footprint "antmicro-footprints:L_Vishay-IHLP-1212AE" (layer "F.Cu")
    (at 91.25 81.55)
    (property "Author" "Antmicro")
    (property "IMax" "6.7 A")
    (property "ISat" "6.7 A")
    (property "License" "Apache-2.0")
    (property "MPN" "IHLP1212AEERR47M11")
    (property "Manufacturer" "Vishay")
    (property "Public" "False")
    (property "Sheetfile" "power-supply.kicad_sch")
    (property "Sheetname" "Power supply")
    (property "Size" "3.0x3.0")
    (property "Val" "470n/6.7A")
    (property "ki_description" "Power Inductor (SMT), 470 nH, 6.7 A, Shielded, 6.7 A")
    (property "ki_keywords" "SMT, INDUCTOR, PASSIVE")
    (attr smd)
    (fp_text reference "L7" (at -2.92 0.145) (layer "F.SilkS")
        (effects (font (size 0.7 0.7) (thickness 0.127)))
    )
    (fp_text value "IHLP1212AEERR47M11" (at 0 0 270) (layer "F.SilkS") hide
        (effects (font (size 1.524 1.524) (thickness 0.05)))
    )
    (fp_text user "License: Apache-2.0" (at -2.35 7.8) (layer "F.Fab") hide
        (effects (font (size 0.7 0.7) (thickness 0.15)) (justify left bottom))
    )
    (fp_text user "${REFERENCE}" (at -2.35 5.4) (layer "F.Fab") hide
        (effects (font (size 0.7 0.7) (thickness 0.15)) (justify left bottom))
    )
    (fp_text user "Author: Antmicro" (at -2.35 6.6) (layer "F.Fab") hide
        (effects (font (size 0.7 0.7) (thickness 0.15)) (justify left bottom))
    )
    (fp_line (start -1.647 -1.6) (end 1.653 -1.6)
      (stroke (width 0.15) (type solid)) (layer "F.SilkS"))
    (fp_line (start -1.647 -0.9) (end -1.647 -1.6)
      (stroke (width 0.15) (type solid)) (layer "F.SilkS"))
    (fp_line (start -1.647 1.6) (end -1.647 0.9)
      (stroke (width 0.15) (type solid)) (layer "F.SilkS"))
    (fp_line (start 1.653 -1.6) (end 1.653 -0.9)
      (stroke (width 0.15) (type solid)) (layer "F.SilkS"))
    (fp_line (start 1.653 0.9) (end 1.653 1.601)
      (stroke (width 0.15) (type solid)) (layer "F.SilkS"))
    (fp_line (start 1.653 1.601) (end -1.647 1.6)
      (stroke (width 0.15) (type solid)) (layer "F.SilkS"))
    (fp_rect (start -2.35 -1.85) (end 2.35 1.85)
      (stroke (width 0.05) (type solid)) (fill none) (layer "F.CrtYd"))
    (fp_rect (start -1.803 -1.601) (end 1.803 1.601)
      (stroke (width 0.15) (type solid)) (fill none) (layer "F.Fab"))
    (pad "1" smd roundrect (at -1.35 0) (size 1.5 1.2) (layers "F.Cu" "F.Paste" "F.Mask") (roundrect_rratio 0.1)
      (net 393 "Net-(U16-SW)") (pintype "passive"))
    (pad "2" smd roundrect (at 1.35 0) (size 1.5 1.2) (layers "F.Cu" "F.Paste" "F.Mask") (roundrect_rratio 0.1)
      (net 359 "Net-(C122-Pad2)") (pintype "passive"))
  )
	(footprint "antmicro-footprints:L_Vishay-IHLP-1212AE" (layer "F.Cu")
    (at 120.139056 79.043104)
    (property "Author" "Antmicro")
    (property "IMax" "6.7 A")
    (property "ISat" "6.7 A")
    (property "License" "Apache-2.0")
    (property "MPN" "IHLP1212AEERR47M11")
    (property "Manufacturer" "Vishay")
    (property "Public" "False")
    (property "Sheetfile" "power-supply.kicad_sch")
    (property "Sheetname" "Power supply")
    (property "Size" "3.0x3.0")
    (property "Val" "470n/6.7A")
    (property "ki_description" "Power Inductor (SMT), 470 nH, 6.7 A, Shielded, 6.7 A")
    (property "ki_keywords" "SMT, INDUCTOR, PASSIVE")
    (attr smd)
    (fp_text reference "L4" (at -2.63 -0.975) (layer "F.SilkS")
        (effects (font (size 0.7 0.7) (thickness 0.127)))
    )
    (fp_text value "IHLP1212AEERR47M11" (at 0 0 270) (layer "F.SilkS") hide
        (effects (font (size 1.524 1.524) (thickness 0.05)))
    )
    (fp_text user "${REFERENCE}" (at -2.35 5.4) (layer "F.Fab") hide
        (effects (font (size 0.7 0.7) (thickness 0.15)) (justify left bottom))
    )
    (fp_text user "License: Apache-2.0" (at -2.35 7.8) (layer "F.Fab") hide
        (effects (font (size 0.7 0.7) (thickness 0.15)) (justify left bottom))
    )
    (fp_text user "Author: Antmicro" (at -2.35 6.6) (layer "F.Fab") hide
        (effects (font (size 0.7 0.7) (thickness 0.15)) (justify left bottom))
    )
    (fp_line (start -1.647 -1.6) (end 1.653 -1.6)
      (stroke (width 0.15) (type solid)) (layer "F.SilkS"))
    (fp_line (start -1.647 -0.9) (end -1.647 -1.6)
      (stroke (width 0.15) (type solid)) (layer "F.SilkS"))
    (fp_line (start -1.647 1.6) (end -1.647 0.9)
      (stroke (width 0.15) (type solid)) (layer "F.SilkS"))
    (fp_line (start 1.653 -1.6) (end 1.653 -0.9)
      (stroke (width 0.15) (type solid)) (layer "F.SilkS"))
    (fp_line (start 1.653 0.9) (end 1.653 1.601)
      (stroke (width 0.15) (type solid)) (layer "F.SilkS"))
    (fp_line (start 1.653 1.601) (end -1.647 1.6)
      (stroke (width 0.15) (type solid)) (layer "F.SilkS"))
    (fp_rect (start -2.35 -1.85) (end 2.35 1.85)
      (stroke (width 0.05) (type solid)) (fill none) (layer "F.CrtYd"))
    (fp_rect (start -1.803 -1.601) (end 1.803 1.601)
      (stroke (width 0.15) (type solid)) (fill none) (layer "F.Fab"))
    (pad "1" smd roundrect (at -1.35 0) (size 1.5 1.2) (layers "F.Cu" "F.Paste" "F.Mask") (roundrect_rratio 0.1)
      (net 390 "Net-(U18-SW)") (pintype "passive"))
    (pad "2" smd roundrect (at 1.35 0) (size 1.5 1.2) (layers "F.Cu" "F.Paste" "F.Mask") (roundrect_rratio 0.1)
      (net 356 "Net-(C119-Pad2)") (pintype "passive"))
  )
	(footprint "antmicro-footprints:R_0402_1005Metric" (layer "F.Cu")
    (at 93.75 76.85)
    (descr "Resistor SMD 0402")
    (tags "resistor SMD 0402")
    (property "Author" "Antmicro")
    (property "License" "Apache-2.0")
    (property "MPN" "CR0402-FX-1002GLF")
    (property "Manufacturer" "Bourns")
    (property "Public" "False")
    (property "Sheetfile" "power-supply.kicad_sch")
    (property "Sheetname" "Power supply")
    (property "Tolerance" "1%")
    (property "Val" "10k")
    (property "ki_description" "SMD Chip Resistor, 10 kohm, ± 1%, 62.5 mW, 0402 [1005 Metric], Thick Film, General Purpose")
    (property "ki_keywords" "0402, SMT, RESISTOR, PASSIVE")
    (attr smd)
    (fp_text reference "R100" (at 1.6 2.165 90) (layer "F.SilkS")
        (effects (font (size 0.7 0.7) (thickness 0.127)))
    )
    (fp_text value "R_10k_0402" (at 0 1.17) (layer "F.Fab")
        (effects (font (size 1 1) (thickness 0.15)))
    )
    (fp_text user "License: Apache-2.0" (at -0.95 5.169) (layer "F.Fab") hide
        (effects (font (size 0.7 0.7) (thickness 0.15)) (justify left bottom))
    )
    (fp_text user "Author: Antmicro" (at -0.95 4.169) (layer "F.Fab") hide
        (effects (font (size 0.7 0.7) (thickness 0.15)) (justify left bottom))
    )
    (fp_text user "${REFERENCE}" (at 0 0) (layer "F.Fab")
        (effects (font (size 0.25 0.25) (thickness 0.04)))
    )
    (fp_rect (start -0.925 -0.47) (end 0.925 0.47)
      (stroke (width 0.05) (type default)) (fill none) (layer "F.CrtYd"))
    (fp_rect (start -0.5 -0.25) (end 0.5 0.25)
      (stroke (width 0.15) (type solid)) (fill none) (layer "F.Fab"))
    (pad "1" smd roundrect (at -0.48 0) (size 0.59 0.64) (layers "F.Cu" "F.Paste" "F.Mask") (roundrect_rratio 0.25)
      (net 289 "Net-(U13-FB)") (pintype "passive"))
    (pad "2" smd roundrect (at 0.48 0) (size 0.59 0.64) (layers "F.Cu" "F.Paste" "F.Mask") (roundrect_rratio 0.25)
      (net 1 "GND") (pintype "passive"))
  )
	(footprint "antmicro-footprints:R_0402_1005Metric" (layer "F.Cu")
    (at 92.8 78.9 180)
    (descr "Resistor SMD 0402")
    (tags "resistor SMD 0402")
    (property "Author" "Antmicro")
    (property "License" "Apache-2.0")
    (property "MPN" "CR0402-FX-4701GLF")
    (property "Manufacturer" "Bourns")
    (property "Public" "False")
    (property "Sheetfile" "power-supply.kicad_sch")
    (property "Sheetname" "Power supply")
    (property "Tolerance" "1%")
    (property "Val" "4k7")
    (property "ki_description" "SMD Chip Resistor, 4.7 kohm, ± 1%, 62.5 mW, 0402 [1005 Metric], Thick Film, General Purpose")
    (property "ki_keywords" "0402, SMT, RESISTOR, PASSIVE")
    (attr smd)
    (fp_text reference "R93" (at -2.03 -2.825) (layer "F.SilkS")
        (effects (font (size 0.7 0.7) (thickness 0.127)))
    )
    (fp_text value "R_4k7_0402" (at 0 1.17) (layer "F.Fab")
        (effects (font (size 1 1) (thickness 0.15)))
    )
    (fp_text user "Author: Antmicro" (at -0.95 4.169 180) (layer "F.Fab") hide
        (effects (font (size 0.7 0.7) (thickness 0.15)) (justify left bottom))
    )
    (fp_text user "License: Apache-2.0" (at -0.95 5.169 180) (layer "F.Fab") hide
        (effects (font (size 0.7 0.7) (thickness 0.15)) (justify left bottom))
    )
    (fp_text user "${REFERENCE}" (at 0 0) (layer "F.Fab")
        (effects (font (size 0.25 0.25) (thickness 0.04)))
    )
    (fp_rect (start -0.925 -0.47) (end 0.925 0.47)
      (stroke (width 0.05) (type default)) (fill none) (layer "F.CrtYd"))
    (fp_rect (start -0.5 -0.25) (end 0.5 0.25)
      (stroke (width 0.15) (type solid)) (fill none) (layer "F.Fab"))
    (pad "1" smd roundrect (at -0.48 0 180) (size 0.59 0.64) (layers "F.Cu" "F.Paste" "F.Mask") (roundrect_rratio 0.25)
      (net 352 "Net-(C106-Pad2)") (pintype "passive"))
    (pad "2" smd roundrect (at 0.48 0 180) (size 0.59 0.64) (layers "F.Cu" "F.Paste" "F.Mask") (roundrect_rratio 0.25)
      (net 289 "Net-(U13-FB)") (pintype "passive"))
  )
	(footprint "antmicro-footprints:PinHeader_1x6_P2.54mm_Drill1.1mm" (layer "F.Cu")
    (at 64.531 104.6)
    (descr "WR-PHD 2.54mm Pin Header, 6 Pin")
    (property "Author" "Antmicro")
    (property "License" "Apache-2.0")
    (property "MPN" "61300611121")
    (property "Manufacturer" "Würth Elektronik")
    (property "Sheetfile" "interfaces.kicad_sch")
    (property "Sheetname" "Interfaces")
    (property "ki_description" "Pin Header, Vertical, Board-to-Board, 2.54 mm, 1 Rows, 6 Contacts, Through Hole Straight, WR-PHD")
    (property "ki_keywords" "VERTICAL, THT, HEADER, CONNECTOR, MALE")
    (attr through_hole)
    (fp_text reference "J7" (at 0.059 3.675 90) (layer "F.SilkS")
        (effects (font (size 0.7 0.7) (thickness 0.127)))
    )
    (fp_text value "PinHeader_1x6_P2.54mm_Drill1.1mm" (at 2.320593 2.138773) (layer "F.Fab")
        (effects (font (size 0.641492 0.641492) (thickness 0.015)))
    )
    (fp_text user "Author: Antmicro" (at -1.5 5.337) (layer "F.Fab") hide
        (effects (font (size 0.7 0.7) (thickness 0.15)) (justify left bottom))
    )
    (fp_text user "License: Apache-2.0" (at -1.5 6.538) (layer "F.Fab") hide
        (effects (font (size 0.7 0.7) (thickness 0.15)) (justify left bottom))
    )
    (fp_text user "${REFERENCE}" (at -1.5 4.137) (layer "F.Fab") hide
        (effects (font (size 0.7 0.7) (thickness 0.15)) (justify left bottom))
    )
    (fp_line (start -1.272 -1.27) (end -1.272 1.269)
      (stroke (width 0.15) (type solid)) (layer "F.SilkS"))
    (fp_line (start -1.272 1.269) (end 13.968 1.269)
      (stroke (width 0.15) (type solid)) (layer "F.SilkS"))
    (fp_line (start 13.968 -1.27) (end -1.272 -1.27)
      (stroke (width 0.15) (type solid)) (layer "F.SilkS"))
    (fp_line (start 13.968 1.269) (end 13.968 -1.27)
      (stroke (width 0.15) (type solid)) (layer "F.SilkS"))
    (fp_line (start -1.5 -1.5) (end 14.18 -1.5)
      (stroke (width 0.05) (type solid)) (layer "F.CrtYd"))
    (fp_line (start -1.5 1.48) (end -1.5 -1.5)
      (stroke (width 0.05) (type solid)) (layer "F.CrtYd"))
    (fp_line (start 14.18 -1.5) (end 14.18 1.48)
      (stroke (width 0.05) (type solid)) (layer "F.CrtYd"))
    (fp_line (start 14.18 1.48) (end -1.5 1.48)
      (stroke (width 0.05) (type solid)) (layer "F.CrtYd"))
    (pad "1" thru_hole circle (at 0 0) (size 1.9 1.9) (drill 1.1) (layers "*.Cu" "*.Mask")
      (net 2 "VCC3V3") (pintype "passive"))
    (pad "2" thru_hole circle (at 2.539 0) (size 1.9 1.9) (drill 1.1) (layers "*.Cu" "*.Mask")
      (net 55 "SPI0_MOSI") (pintype "passive"))
    (pad "3" thru_hole circle (at 5.078 0) (size 1.9 1.9) (drill 1.1) (layers "*.Cu" "*.Mask")
      (net 56 "SPI0_MISO") (pintype "passive"))
    (pad "4" thru_hole circle (at 7.618 0) (size 1.9 1.9) (drill 1.1) (layers "*.Cu" "*.Mask")
      (net 54 "SPI0_CLK") (pintype "passive"))
    (pad "5" thru_hole circle (at 10.159 0) (size 1.9 1.9) (drill 1.1) (layers "*.Cu" "*.Mask")
      (net 53 "SPI0_CS_N") (pintype "passive"))
    (pad "6" thru_hole circle (at 12.698 0) (size 1.9 1.9) (drill 1.1) (layers "*.Cu" "*.Mask")
      (net 1 "GND") (pintype "passive"))
  )
	(footprint "antmicro-footprints:R_0402_1005Metric" (layer "F.Cu")
    (at 127.225 130.525 180)
    (descr "Resistor SMD 0402")
    (tags "resistor SMD 0402")
    (property "Author" "Antmicro")
    (property "License" "Apache-2.0")
    (property "MPN" "CR0402-FX-1202GLF")
    (property "Manufacturer" "Bourns")
    (property "Public" "False")
    (property "Sheetfile" "interfaces.kicad_sch")
    (property "Sheetname" "Interfaces")
    (property "Tolerance" "1%")
    (property "Val" "12k")
    (property "ki_description" "SMD Chip Resistor, 12 kohm, ± 1%, 62.5 mW, 0402 [1005 Metric], Thick Film, General Purpose")
    (property "ki_keywords" "0402, SMT, RESISTOR, PASSIVE")
    (attr smd)
    (fp_text reference "R75" (at -2.605 -0.155) (layer "F.SilkS")
        (effects (font (size 0.7 0.7) (thickness 0.127)))
    )
    (fp_text value "R_12k_0402" (at 0 1.17) (layer "F.Fab")
        (effects (font (size 1 1) (thickness 0.15)))
    )
    (fp_text user "${REFERENCE}" (at 0 0) (layer "F.Fab")
        (effects (font (size 0.25 0.25) (thickness 0.04)))
    )
    (fp_text user "Author: Antmicro" (at -0.95 4.169 180) (layer "F.Fab") hide
        (effects (font (size 0.7 0.7) (thickness 0.15)) (justify left bottom))
    )
    (fp_text user "License: Apache-2.0" (at -0.95 5.169 180) (layer "F.Fab") hide
        (effects (font (size 0.7 0.7) (thickness 0.15)) (justify left bottom))
    )
    (fp_rect (start -0.925 -0.47) (end 0.925 0.47)
      (stroke (width 0.05) (type default)) (fill none) (layer "F.CrtYd"))
    (fp_rect (start -0.5 -0.25) (end 0.5 0.25)
      (stroke (width 0.15) (type solid)) (fill none) (layer "F.Fab"))
    (pad "1" smd roundrect (at -0.48 0 180) (size 0.59 0.64) (layers "F.Cu" "F.Paste" "F.Mask") (roundrect_rratio 0.25)
      (net 1 "GND") (pintype "passive"))
    (pad "2" smd roundrect (at 0.48 0 180) (size 0.59 0.64) (layers "F.Cu" "F.Paste" "F.Mask") (roundrect_rratio 0.25)
      (net 405 "Net-(U8-RBIAS)") (pintype "passive"))
  )
)
